(kicad_pcb
	(version 20260206)
	(generator "pcbnew")
	(generator_version "10.0")
	(general
		(thickness 1.6)
		(legacy_teardrops no)
	)
	(paper "A4")
	(title_block
		(title "01162023_DA0F0TEBIF0_F0T_Expander_BD_F_brd_V02_OCP.brd")
		(comment 1 "Grand Teton / footprints 4805-4813 of 9728")
	)
	(layers
		(0 "F.Cu" signal "TOP")
		(4 "In1.Cu" signal "GND")
		(6 "In2.Cu" signal "VCC")
		(8 "In3.Cu" signal "VCC1")
		(10 "In4.Cu" signal "GND1")
		(12 "In5.Cu" signal "IN1")
		(14 "In6.Cu" signal "GND2")
		(16 "In7.Cu" signal "IN2")
		(18 "In8.Cu" signal "GND3")
		(20 "In9.Cu" signal "IN3")
		(22 "In10.Cu" signal "GND4")
		(24 "In11.Cu" signal "IN4")
		(26 "In12.Cu" signal "GND5")
		(28 "In13.Cu" signal "IN5")
		(30 "In14.Cu" signal "GND6")
		(32 "In15.Cu" signal "IN6")
		(34 "In16.Cu" signal "GND7")
		(2 "B.Cu" signal "BOTTOM")
		(9 "F.Adhes" user "F.Adhesive")
		(11 "B.Adhes" user "B.Adhesive")
		(13 "F.Paste" user "Package Geometry/Pastemask Top")
		(15 "B.Paste" user "Package Geometry/Pastemask Bottom")
		(5 "F.SilkS" user "Ref Des/Silkscreen Top")
		(7 "B.SilkS" user "Ref Des/Silkscreen Bottom")
		(1 "F.Mask" user "Board Geometry/Soldermask Top")
		(3 "B.Mask" user "Board Geometry/Soldermask Bottom")
		(17 "Dwgs.User" user "User.Drawings")
		(19 "Cmts.User" user "User.Comments")
		(21 "Eco1.User" user "User.Eco1")
		(23 "Eco2.User" user "User.Eco2")
		(25 "Edge.Cuts" user "Board Geometry/Outline")
		(27 "Margin" user)
		(31 "F.CrtYd" user "Package Geometry/Place Bound Top")
		(29 "B.CrtYd" user "Package Geometry/Place Bound Bottom")
		(35 "F.Fab" user "Ref Des/Assembly Top")
		(33 "B.Fab" user "Ref Des/Assembly Bottom")
	)
	(footprint ""
		(layer "F.Cu")
		(at 178.619912 -343.952322 90)
		(property "Reference" "C2527"
			(at 0 0 90)
			(layer "F.SilkS")
			(hide yes)
			(effects
				(font
					(size 1.27 1.27)
				)
			)
		)
		(property "Value" ""
			(at 0 0 90)
			(layer "F.Fab")
			(effects
				(font
					(size 1.27 1.27)
				)
			)
		)
		(duplicate_pad_numbers_are_jumpers no)
		(fp_line
			(start 0.299974 -0.150114)
			(end 0.299974 0.150114)
			(stroke
				(width 0.1)
				(type default)
			)
			(layer "F.Fab")
		)
		(fp_line
			(start -0.299974 -0.150114)
			(end 0.299974 -0.150114)
			(stroke
				(width 0.1)
				(type default)
			)
			(layer "F.Fab")
		)
		(fp_line
			(start 0.299974 0.150114)
			(end -0.299974 0.150114)
			(stroke
				(width 0.1)
				(type default)
			)
			(layer "F.Fab")
		)
		(fp_line
			(start -0.299974 0.150114)
			(end -0.299974 -0.150114)
			(stroke
				(width 0.1)
				(type default)
			)
			(layer "F.Fab")
		)
		(pad "1" smd rect
			(at -0.2667 0 90)
			(size 0.3048 0.381)
			(layers "F.Cu" "F.Mask" "F.Paste")
			(net "P5E_PEX1_STN4_TX_DN<72>")
		)
		(pad "2" smd rect
			(at 0.2667 0 90)
			(size 0.3048 0.381)
			(layers "F.Cu" "F.Mask" "F.Paste")
			(net "P5E_PEX1_STN4_TX_C_DN<72>")
		)
	)
	(footprint ""
		(layer "F.Cu")
		(at 135.358124 -72.766682 90)
		(property "Reference" "PC845"
			(at 0 0 90)
			(layer "F.SilkS")
			(hide yes)
			(effects
				(font
					(size 1.27 1.27)
				)
			)
		)
		(property "Value" ""
			(at 0 0 90)
			(layer "F.Fab")
			(effects
				(font
					(size 1.27 1.27)
				)
			)
		)
		(duplicate_pad_numbers_are_jumpers no)
		(fp_line
			(start 0.7874 -0.4064)
			(end 0.7874 0.4064)
			(stroke
				(width 0.1524)
				(type default)
			)
			(layer "F.SilkS")
		)
		(fp_line
			(start -0.7874 -0.4064)
			(end 0.7874 -0.4064)
			(stroke
				(width 0.1524)
				(type default)
			)
			(layer "F.SilkS")
		)
		(fp_line
			(start 0.7874 0.4064)
			(end -0.7874 0.4064)
			(stroke
				(width 0.1524)
				(type default)
			)
			(layer "F.SilkS")
		)
		(fp_line
			(start -0.7874 0.4064)
			(end -0.7874 -0.4064)
			(stroke
				(width 0.1524)
				(type default)
			)
			(layer "F.SilkS")
		)
		(fp_line
			(start -0.12065 -0.305054)
			(end -0.12065 -0.2794)
			(stroke
				(width 0.1)
				(type default)
			)
			(layer "F.Fab")
		)
		(fp_line
			(start -0.67945 -0.305054)
			(end -0.12065 -0.305054)
			(stroke
				(width 0.1)
				(type default)
			)
			(layer "F.Fab")
		)
		(fp_line
			(start 0.67945 -0.3048)
			(end 0.67945 0.3048)
			(stroke
				(width 0.1)
				(type default)
			)
			(layer "F.Fab")
		)
		(fp_line
			(start 0.12065 -0.3048)
			(end 0.67945 -0.3048)
			(stroke
				(width 0.1)
				(type default)
			)
			(layer "F.Fab")
		)
		(fp_line
			(start 0.12065 -0.2794)
			(end 0.12065 -0.3048)
			(stroke
				(width 0.1)
				(type default)
			)
			(layer "F.Fab")
		)
		(fp_line
			(start -0.12065 -0.2794)
			(end 0.12065 -0.2794)
			(stroke
				(width 0.1)
				(type default)
			)
			(layer "F.Fab")
		)
		(fp_line
			(start 0.120396 0.2794)
			(end -0.12065 0.2794)
			(stroke
				(width 0.1)
				(type default)
			)
			(layer "F.Fab")
		)
		(fp_line
			(start -0.12065 0.2794)
			(end -0.12065 0.3048)
			(stroke
				(width 0.1)
				(type default)
			)
			(layer "F.Fab")
		)
		(fp_line
			(start 0.67945 0.3048)
			(end 0.120396 0.3048)
			(stroke
				(width 0.1)
				(type default)
			)
			(layer "F.Fab")
		)
		(fp_line
			(start 0.120396 0.3048)
			(end 0.120396 0.2794)
			(stroke
				(width 0.1)
				(type default)
			)
			(layer "F.Fab")
		)
		(fp_line
			(start -0.12065 0.3048)
			(end -0.67945 0.3048)
			(stroke
				(width 0.1)
				(type default)
			)
			(layer "F.Fab")
		)
		(fp_line
			(start -0.67945 0.3048)
			(end -0.67945 -0.305054)
			(stroke
				(width 0.1)
				(type default)
			)
			(layer "F.Fab")
		)
		(pad "1" smd circle
			(at -0.40005 0 90)
			(size 0 0)
			(layers "F.Cu" "F.Mask" "F.Paste")
			(net "P12V_SSD4_CO_MODE")
		)
		(pad "2" smd circle
			(at 0.40005 0 90)
			(size 0 0)
			(layers "F.Cu" "F.Mask" "F.Paste")
			(net "GND")
		)
	)
	(footprint ""
		(layer "F.Cu")
		(at 126.221236 -173.991524)
		(property "Reference" "R1089"
			(at 0 0 0)
			(layer "F.SilkS")
			(hide yes)
			(effects
				(font
					(size 1.27 1.27)
				)
			)
		)
		(property "Value" ""
			(at 0 0 0)
			(layer "F.Fab")
			(effects
				(font
					(size 1.27 1.27)
				)
			)
		)
		(duplicate_pad_numbers_are_jumpers no)
		(fp_line
			(start 0.7874 0.4064)
			(end -0.7874 0.4064)
			(stroke
				(width 0.1524)
				(type default)
			)
			(layer "F.SilkS")
		)
		(fp_line
			(start -0.67945 -0.305054)
			(end -0.12065 -0.305054)
			(stroke
				(width 0.1)
				(type default)
			)
			(layer "F.Fab")
		)
		(fp_line
			(start -0.67945 0.3048)
			(end -0.67945 -0.305054)
			(stroke
				(width 0.1)
				(type default)
			)
			(layer "F.Fab")
		)
		(fp_line
			(start -0.12065 -0.305054)
			(end -0.12065 -0.2794)
			(stroke
				(width 0.1)
				(type default)
			)
			(layer "F.Fab")
		)
		(fp_line
			(start -0.12065 -0.2794)
			(end 0.12065 -0.2794)
			(stroke
				(width 0.1)
				(type default)
			)
			(layer "F.Fab")
		)
		(fp_line
			(start -0.12065 0.2794)
			(end -0.12065 0.3048)
			(stroke
				(width 0.1)
				(type default)
			)
			(layer "F.Fab")
		)
		(fp_line
			(start -0.12065 0.3048)
			(end -0.67945 0.3048)
			(stroke
				(width 0.1)
				(type default)
			)
			(layer "F.Fab")
		)
		(fp_line
			(start 0.120396 0.2794)
			(end -0.12065 0.2794)
			(stroke
				(width 0.1)
				(type default)
			)
			(layer "F.Fab")
		)
		(fp_line
			(start 0.120396 0.3048)
			(end 0.120396 0.2794)
			(stroke
				(width 0.1)
				(type default)
			)
			(layer "F.Fab")
		)
		(fp_line
			(start 0.12065 -0.3048)
			(end 0.67945 -0.3048)
			(stroke
				(width 0.1)
				(type default)
			)
			(layer "F.Fab")
		)
		(fp_line
			(start 0.12065 -0.2794)
			(end 0.12065 -0.3048)
			(stroke
				(width 0.1)
				(type default)
			)
			(layer "F.Fab")
		)
		(fp_line
			(start 0.67945 -0.3048)
			(end 0.67945 0.3048)
			(stroke
				(width 0.1)
				(type default)
			)
			(layer "F.Fab")
		)
		(fp_line
			(start 0.67945 0.3048)
			(end 0.120396 0.3048)
			(stroke
				(width 0.1)
				(type default)
			)
			(layer "F.Fab")
		)
		(pad "1" smd circle
			(at -0.40005 0)
			(size 0 0)
			(layers "F.Cu" "F.Mask" "F.Paste")
			(net "CLK_100M_DB2000QL_PEX1_S1_R_DN")
		)
		(pad "2" smd circle
			(at 0.40005 0)
			(size 0 0)
			(layers "F.Cu" "F.Mask" "F.Paste")
			(net "CLK_100M_DB2000QL_PEX1_S1_DN")
		)
	)
	(footprint ""
		(layer "F.Cu")
		(at 32.119062 -59.574684 90)
		(property "Reference" "PC516"
			(at 0 0 90)
			(layer "F.SilkS")
			(hide yes)
			(effects
				(font
					(size 1.27 1.27)
				)
			)
		)
		(property "Value" ""
			(at 0 0 90)
			(layer "F.Fab")
			(effects
				(font
					(size 1.27 1.27)
				)
			)
		)
		(duplicate_pad_numbers_are_jumpers no)
		(fp_line
			(start 0.7874 -0.4064)
			(end 0.7874 0.4064)
			(stroke
				(width 0.1524)
				(type default)
			)
			(layer "F.SilkS")
		)
		(fp_line
			(start -0.7874 -0.4064)
			(end 0.7874 -0.4064)
			(stroke
				(width 0.1524)
				(type default)
			)
			(layer "F.SilkS")
		)
		(fp_line
			(start 0.7874 0.4064)
			(end -0.7874 0.4064)
			(stroke
				(width 0.1524)
				(type default)
			)
			(layer "F.SilkS")
		)
		(fp_line
			(start -0.7874 0.4064)
			(end -0.7874 -0.4064)
			(stroke
				(width 0.1524)
				(type default)
			)
			(layer "F.SilkS")
		)
		(fp_line
			(start -0.12065 -0.305054)
			(end -0.12065 -0.2794)
			(stroke
				(width 0.1)
				(type default)
			)
			(layer "F.Fab")
		)
		(fp_line
			(start -0.67945 -0.305054)
			(end -0.12065 -0.305054)
			(stroke
				(width 0.1)
				(type default)
			)
			(layer "F.Fab")
		)
		(fp_line
			(start 0.67945 -0.3048)
			(end 0.67945 0.3048)
			(stroke
				(width 0.1)
				(type default)
			)
			(layer "F.Fab")
		)
		(fp_line
			(start 0.12065 -0.3048)
			(end 0.67945 -0.3048)
			(stroke
				(width 0.1)
				(type default)
			)
			(layer "F.Fab")
		)
		(fp_line
			(start 0.12065 -0.2794)
			(end 0.12065 -0.3048)
			(stroke
				(width 0.1)
				(type default)
			)
			(layer "F.Fab")
		)
		(fp_line
			(start -0.12065 -0.2794)
			(end 0.12065 -0.2794)
			(stroke
				(width 0.1)
				(type default)
			)
			(layer "F.Fab")
		)
		(fp_line
			(start 0.120396 0.2794)
			(end -0.12065 0.2794)
			(stroke
				(width 0.1)
				(type default)
			)
			(layer "F.Fab")
		)
		(fp_line
			(start -0.12065 0.2794)
			(end -0.12065 0.3048)
			(stroke
				(width 0.1)
				(type default)
			)
			(layer "F.Fab")
		)
		(fp_line
			(start 0.67945 0.3048)
			(end 0.120396 0.3048)
			(stroke
				(width 0.1)
				(type default)
			)
			(layer "F.Fab")
		)
		(fp_line
			(start 0.120396 0.3048)
			(end 0.120396 0.2794)
			(stroke
				(width 0.1)
				(type default)
			)
			(layer "F.Fab")
		)
		(fp_line
			(start -0.12065 0.3048)
			(end -0.67945 0.3048)
			(stroke
				(width 0.1)
				(type default)
			)
			(layer "F.Fab")
		)
		(fp_line
			(start -0.67945 0.3048)
			(end -0.67945 -0.305054)
			(stroke
				(width 0.1)
				(type default)
			)
			(layer "F.Fab")
		)
		(pad "1" smd circle
			(at -0.40005 0 90)
			(size 0 0)
			(layers "F.Cu" "F.Mask" "F.Paste")
			(net "P5V_AUX")
		)
		(pad "2" smd circle
			(at 0.40005 0 90)
			(size 0 0)
			(layers "F.Cu" "F.Mask" "F.Paste")
			(net "GND")
		)
	)
	(footprint ""
		(layer "F.Cu")
		(at 338.074 -146.939 180)
		(property "Reference" "R4832"
			(at 0 0 180)
			(layer "F.SilkS")
			(hide yes)
			(effects
				(font
					(size 1.27 1.27)
				)
			)
		)
		(property "Value" ""
			(at 0 0 180)
			(layer "F.Fab")
			(effects
				(font
					(size 1.27 1.27)
				)
			)
		)
		(duplicate_pad_numbers_are_jumpers no)
		(fp_line
			(start 0.7874 0.4064)
			(end -0.7874 0.4064)
			(stroke
				(width 0.1524)
				(type default)
			)
			(layer "F.SilkS")
		)
		(fp_line
			(start 0.7874 -0.4064)
			(end 0.7874 0.4064)
			(stroke
				(width 0.1524)
				(type default)
			)
			(layer "F.SilkS")
		)
		(fp_line
			(start -0.7874 0.4064)
			(end -0.7874 -0.4064)
			(stroke
				(width 0.1524)
				(type default)
			)
			(layer "F.SilkS")
		)
		(fp_line
			(start -0.7874 -0.4064)
			(end 0.7874 -0.4064)
			(stroke
				(width 0.1524)
				(type default)
			)
			(layer "F.SilkS")
		)
		(fp_line
			(start 0.67945 0.3048)
			(end 0.120396 0.3048)
			(stroke
				(width 0.1)
				(type default)
			)
			(layer "F.Fab")
		)
		(fp_line
			(start 0.67945 -0.3048)
			(end 0.67945 0.3048)
			(stroke
				(width 0.1)
				(type default)
			)
			(layer "F.Fab")
		)
		(fp_line
			(start 0.12065 -0.2794)
			(end 0.12065 -0.3048)
			(stroke
				(width 0.1)
				(type default)
			)
			(layer "F.Fab")
		)
		(fp_line
			(start 0.12065 -0.3048)
			(end 0.67945 -0.3048)
			(stroke
				(width 0.1)
				(type default)
			)
			(layer "F.Fab")
		)
		(fp_line
			(start 0.120396 0.3048)
			(end 0.120396 0.2794)
			(stroke
				(width 0.1)
				(type default)
			)
			(layer "F.Fab")
		)
		(fp_line
			(start 0.120396 0.2794)
			(end -0.12065 0.2794)
			(stroke
				(width 0.1)
				(type default)
			)
			(layer "F.Fab")
		)
		(fp_line
			(start -0.12065 0.3048)
			(end -0.67945 0.3048)
			(stroke
				(width 0.1)
				(type default)
			)
			(layer "F.Fab")
		)
		(fp_line
			(start -0.12065 0.2794)
			(end -0.12065 0.3048)
			(stroke
				(width 0.1)
				(type default)
			)
			(layer "F.Fab")
		)
		(fp_line
			(start -0.12065 -0.2794)
			(end 0.12065 -0.2794)
			(stroke
				(width 0.1)
				(type default)
			)
			(layer "F.Fab")
		)
		(fp_line
			(start -0.12065 -0.305054)
			(end -0.12065 -0.2794)
			(stroke
				(width 0.1)
				(type default)
			)
			(layer "F.Fab")
		)
		(fp_line
			(start -0.67945 0.3048)
			(end -0.67945 -0.305054)
			(stroke
				(width 0.1)
				(type default)
			)
			(layer "F.Fab")
		)
		(fp_line
			(start -0.67945 -0.305054)
			(end -0.12065 -0.305054)
			(stroke
				(width 0.1)
				(type default)
			)
			(layer "F.Fab")
		)
		(pad "1" smd circle
			(at -0.40005 0 180)
			(size 0 0)
			(layers "F.Cu" "F.Mask" "F.Paste")
			(net "SSD14_PEX_PWR_EN")
		)
		(pad "2" smd circle
			(at 0.40005 0 180)
			(size 0 0)
			(layers "F.Cu" "F.Mask" "F.Paste")
			(net "SSD14_PEX_PWR_EN_R")
		)
	)
	(footprint ""
		(layer "F.Cu")
		(at 275.992336 -31.825184 180)
		(property "Reference" "C498"
			(at 0 0 180)
			(layer "F.SilkS")
			(hide yes)
			(effects
				(font
					(size 1.27 1.27)
				)
			)
		)
		(property "Value" ""
			(at 0 0 180)
			(layer "F.Fab")
			(effects
				(font
					(size 1.27 1.27)
				)
			)
		)
		(duplicate_pad_numbers_are_jumpers no)
		(fp_line
			(start 0.299974 0.150114)
			(end -0.299974 0.150114)
			(stroke
				(width 0.1)
				(type default)
			)
			(layer "F.Fab")
		)
		(fp_line
			(start 0.299974 -0.150114)
			(end 0.299974 0.150114)
			(stroke
				(width 0.1)
				(type default)
			)
			(layer "F.Fab")
		)
		(fp_line
			(start -0.299974 0.150114)
			(end -0.299974 -0.150114)
			(stroke
				(width 0.1)
				(type default)
			)
			(layer "F.Fab")
		)
		(fp_line
			(start -0.299974 -0.150114)
			(end 0.299974 -0.150114)
			(stroke
				(width 0.1)
				(type default)
			)
			(layer "F.Fab")
		)
		(pad "1" smd rect
			(at -0.2667 0 180)
			(size 0.3048 0.381)
			(layers "F.Cu" "F.Mask" "F.Paste")
			(net "P5E_PEX2_STN2_TX_DN<42>")
		)
		(pad "2" smd rect
			(at 0.2667 0 180)
			(size 0.3048 0.381)
			(layers "F.Cu" "F.Mask" "F.Paste")
			(net "P5E_PEX2_STN2_TX_C_DN<42>")
		)
	)
	(footprint ""
		(layer "F.Cu")
		(at 20.434554 -34.546286 180)
		(property "Reference" "C65"
			(at 0 0 180)
			(layer "F.SilkS")
			(hide yes)
			(effects
				(font
					(size 1.27 1.27)
				)
			)
		)
		(property "Value" ""
			(at 0 0 180)
			(layer "F.Fab")
			(effects
				(font
					(size 1.27 1.27)
				)
			)
		)
		(duplicate_pad_numbers_are_jumpers no)
		(fp_line
			(start 0.299974 0.150114)
			(end -0.299974 0.150114)
			(stroke
				(width 0.1)
				(type default)
			)
			(layer "F.Fab")
		)
		(fp_line
			(start 0.299974 -0.150114)
			(end 0.299974 0.150114)
			(stroke
				(width 0.1)
				(type default)
			)
			(layer "F.Fab")
		)
		(fp_line
			(start -0.299974 0.150114)
			(end -0.299974 -0.150114)
			(stroke
				(width 0.1)
				(type default)
			)
			(layer "F.Fab")
		)
		(fp_line
			(start -0.299974 -0.150114)
			(end 0.299974 -0.150114)
			(stroke
				(width 0.1)
				(type default)
			)
			(layer "F.Fab")
		)
		(pad "1" smd rect
			(at -0.2667 0 180)
			(size 0.3048 0.381)
			(layers "F.Cu" "F.Mask" "F.Paste")
			(net "P5E_PEX0_STN2_TX_DP<47>")
		)
		(pad "2" smd rect
			(at 0.2667 0 180)
			(size 0.3048 0.381)
			(layers "F.Cu" "F.Mask" "F.Paste")
			(net "P5E_PEX0_STN2_TX_C_DP<47>")
		)
	)
	(footprint ""
		(layer "F.Cu")
		(at 354.889562 -313.620404 180)
		(property "Reference" "R5795"
			(at 0 0 180)
			(layer "F.SilkS")
			(hide yes)
			(effects
				(font
					(size 1.27 1.27)
				)
			)
		)
		(property "Value" ""
			(at 0 0 180)
			(layer "F.Fab")
			(effects
				(font
					(size 1.27 1.27)
				)
			)
		)
		(duplicate_pad_numbers_are_jumpers no)
		(fp_line
			(start 2.576322 1.1303)
			(end -2.576322 1.1303)
			(stroke
				(width 0.1524)
				(type default)
			)
			(layer "F.SilkS")
		)
		(fp_line
			(start 2.576322 -1.1303)
			(end 2.576322 1.1303)
			(stroke
				(width 0.1524)
				(type default)
			)
			(layer "F.SilkS")
		)
		(fp_line
			(start -2.576322 1.1303)
			(end -2.576322 -1.1303)
			(stroke
				(width 0.1524)
				(type default)
			)
			(layer "F.SilkS")
		)
		(fp_line
			(start -2.576322 -1.1303)
			(end 2.576322 -1.1303)
			(stroke
				(width 0.1524)
				(type default)
			)
			(layer "F.SilkS")
		)
		(fp_line
			(start 1.649984 0.899922)
			(end 1.649984 -0.899922)
			(stroke
				(width 0.1)
				(type default)
			)
			(layer "F.Fab")
		)
		(fp_line
			(start 1.649984 -0.899922)
			(end -1.649984 -0.899922)
			(stroke
				(width 0.1)
				(type default)
			)
			(layer "F.Fab")
		)
		(fp_line
			(start -1.649984 0.899922)
			(end 1.649984 0.899922)
			(stroke
				(width 0.1)
				(type default)
			)
			(layer "F.Fab")
		)
		(fp_line
			(start -1.649984 -0.899922)
			(end -1.649984 0.899922)
			(stroke
				(width 0.1)
				(type default)
			)
			(layer "F.Fab")
		)
		(pad "1A" smd rect
			(at -1.700022 0 180)
			(size 1.4986 2.0066)
			(layers "F.Cu" "F.Mask" "F.Paste")
			(net "P0V8_PEX3")
		)
		(pad "1B" smd rect
			(at -1.077722 0 180)
			(size 0.254 0.508)
			(layers "F.Cu" "F.Mask" "F.Paste")
			(net "P0V8_PEX3")
		)
		(pad "2A" smd rect
			(at 1.700022 0 180)
			(size 1.4986 2.0066)
			(layers "F.Cu" "F.Mask" "F.Paste")
			(net "P0V8_SERDES_VDDA_PEX3")
		)
		(pad "2B" smd rect
			(at 1.077722 0 180)
			(size 0.254 0.508)
			(layers "F.Cu" "F.Mask" "F.Paste")
			(net "P0V8_SERDES_VDDA_PEX3")
		)
	)
	(footprint ""
		(layer "F.Cu")
		(at 143.840708 -350.098614 90)
		(property "Reference" "C2260"
			(at 0 0 90)
			(layer "F.SilkS")
			(hide yes)
			(effects
				(font
					(size 1.27 1.27)
				)
			)
		)
		(property "Value" ""
			(at 0 0 90)
			(layer "F.Fab")
			(effects
				(font
					(size 1.27 1.27)
				)
			)
		)
		(duplicate_pad_numbers_are_jumpers no)
		(fp_line
			(start 0.299974 -0.150114)
			(end 0.299974 0.150114)
			(stroke
				(width 0.1)
				(type default)
			)
			(layer "F.Fab")
		)
		(fp_line
			(start -0.299974 -0.150114)
			(end 0.299974 -0.150114)
			(stroke
				(width 0.1)
				(type default)
			)
			(layer "F.Fab")
		)
		(fp_line
			(start 0.299974 0.150114)
			(end -0.299974 0.150114)
			(stroke
				(width 0.1)
				(type default)
			)
			(layer "F.Fab")
		)
		(fp_line
			(start -0.299974 0.150114)
			(end -0.299974 -0.150114)
			(stroke
				(width 0.1)
				(type default)
			)
			(layer "F.Fab")
		)
		(pad "1" smd rect
			(at -0.2667 0 90)
			(size 0.3048 0.381)
			(layers "F.Cu" "F.Mask" "F.Paste")
			(net "P5E_PEX1_STN5_TX_DN<87>")
		)
		(pad "2" smd rect
			(at 0.2667 0 90)
			(size 0.3048 0.381)
			(layers "F.Cu" "F.Mask" "F.Paste")
			(net "P5E_PEX1_STN5_TX_C_DN<87>")
		)
	)
)
